FILE_TYPE = CONNECTIVITY;
{Allegro Design Entry HDL 16.6-p007 (v16-6-112F) 10/10/2012}
"PAGE_NUMBER" = 210;
0"NC";
1"GND\g";
2"GND\g";
3"VR_FET_SW_P12V_STBY_PVCCIN_CPU1\g";
4"GND\g";
5"GND\g";
6"P5V_STBY\g";
7"PVSA_CPU1\g";
8"PVSA_CPU1\g";
9"GND\g";
10"GND\g";
11"GND\g";
12"GND\g";
13"PVSA_CPU1\g";
14"GND\g";
15"VSENSE_PVSA_CPU1_SKT_VSEN";
16"VR_PVSA_CPU1_PHASE_SW"VOLTAGE"5";
17"A_TSENSE_PVSA_CPU1";
18"VR_PVSA_CPU1_BIREF1";
19"VR_PVSA_CPU1_BOOT_R";
20"VR_PVSA_CPU1_PHASE"VOLTAGE"5";
21"VR_PVSA_CPU1_BOOT";
22"VR_PVSA_CPU1_PWM";
23"VSENSE_PVSA_CPU1_P";
24"VSENSE_PVSA_CPU1_N";
25"VR_PVSA_CPU1_OCSET";
26"VSENSE_PVSA_CPU1_SKT_VRTN";
27"UN$210$3D01R5F-GP$I59$2";
28"ISENSE_PVSA_CPU1_IMON";
29"NC_PVSA_CPU1_P31";
30"VR_PVSA_CPU1_VCIN"VOLTAGE"5";
31"TP_PVSA_CPU1_GL_1";
32"TP_PVSA_CPU1_GL_0";
%"INDUCTOR"
"1","(-1900,3300)","0","mstr_discrete","I10";
;
CDS_SEC"1"
SEC_TYPE"SM"
SEC"1"
CDS_LOCATION"L1C1"
ROOM"PVSA_CPU1_PWR_VR"
CDS_LIB"mstr_discrete"
VALUE"0.3UH"
LOCATION"L1C1"
PACK_TYPE"SM"
MATERIAL"IND"
PART_NUMBER"D92183-036";
"INA\NAC"
$PN"1"16;
"INB\NAC"
$PN"2"13;
%"CAPP"
"1","(-1325,1375)","0","mstr_discrete","I12";
;
CDS_SEC"1"
CDS_LIB"mstr_discrete"
CDS_LOCATION"C9N11"
VOLTAGE"2.5V"
ROOM"PVSA_CPU1_DECAP_VR"
BOM_COST"PROC_VRD_VCCIN_CPU0"
SEC_TYPE"3018"
SEC"1"
MATERIAL"ALUM"
PACK_TYPE"3018"
TOLERANCE"20%"
VALUE"470UF"
LOCATION"C9N11"
PART_NUMBER"699013-049";
"B"
$PN"2"1;
"A"
$PN"1"8;
%"GND"
"1","(-1325,975)","0","mstr_symbols","I13";
;
BODY_TYPE"PLUMBING"
CDS_LIB"mstr_symbols"
SIZE"1B"
VOLTAGE"0"
ROOM"PVSA_CPU1_DECAP_VR"
BOM_COST"PROC_VRD_VCCIN_CPU0"
HDL_POWER"GND";
"A\NAC"1;
%"CAPP"
"1","(-1575,1375)","2","mstr_discrete","I14";
;
CDS_SEC"1"
CDS_LIB"mstr_discrete"
CDS_LOCATION"C9N20"
ROOM"PVSA_CPU1_DECAP_VR"
BOM_COST"PROC_VRD_VCCIN_CPU0"
SEC"1"
SEC_TYPE"3018"
PART_NUMBER"699013-049"
PACK_TYPE"3018"
MATERIAL"ALUM"
VOLTAGE"2.5V"
TOLERANCE"20%"
VALUE"470UF"
LOCATION"C9N20";
"B"
$PN"2"1;
"A"
$PN"1"8;
%"GND"
"1","(-3100,2900)","0","mstr_symbols","I15";
;
ROOM"PVSA_CPU1_PWR_VR"
BOM_COST"PROC_VRD_VCCIN_CPU0"
BODY_TYPE"PLUMBING"
CDS_LIB"mstr_symbols"
VOLTAGE"0"
HDL_POWER"GND"
SIZE"1B";
"A\NAC"2;
%"RES"
"1","(-5700,4425)","0","mstr_discrete","I20";
;
CDS_SEC"1"
ROOM"PVSA_CPU1_PWR_VR"
CDS_LIB"mstr_discrete"
CDS_LOCATION"R9N3"
SEC_TYPE"0402"
SEC"1"
WATTAGE"1/16W"
VALUE"1.0"
TOLERANCE"1%"
LOCATION"R9N3"
PACK_TYPE"0402"
PART_NUMBER"G21796-090"
MATERIAL"CHIP";
"B"
$PN"2"6;
"A"
$PN"1"30;
%"VCC_CORE"
"1","(-7400,4225)","0","mstr_symbols","I21";
;
CDS_LIB"mstr_symbols"
HDL_POWER"VR_FET_SW_P12V_STBY_PVCCIN_CPU1";
"A"3;
%"CAP"
"1","(-5375,3850)","0","mstr_discrete","I22";
;
CDS_SEC"1"
CDS_LIB"mstr_discrete"
SEC_TYPE"0402"
SEC"1"
CDS_LOCATION"C1C4"
ROOM"PVSA_CPU1_PWR_VR"
MATERIAL"X7R"
PACK_TYPE"0402"
TOLERANCE"10%"
VOLTAGE"16V"
LOCATION"C1C4"
VALUE"0.22UF"
PART_NUMBER"A36096-155";
"A"
$PN"1"6;
"B"
$PN"2"5;
%"CAP_A"
"1","(-5500,3850)","2","dev_discrete","I23";
;
CDS_LOCATION"C1C3"
CDS_LIB"dev_discrete"
CDS_SEC"1"
SEC_TYPE"0402V"
SEC"1"
ROOM"PVSA_CPU1_PWR_VR"
MATERIAL"X6S"
VOLTAGE"6.3V"
TOLERANCE"10%"
VALUE"1.0UF"
LOCATION"C1C3"
PACK_TYPE"0402V"
PART_NUMBER"D97712-004";
"B"
$PN"2"5;
"A"
$PN"1"6;
%"CAP"
"1","(-6125,3250)","2","mstr_discrete","I24";
;
CDS_SEC"1"
CDS_LIB"mstr_discrete"
SEC_TYPE"0402"
ROOM"PVSA_CPU1_PWR_VR"
SPOF"TRUE"
SEC"1"
CDS_LOCATION"C1C12"
MATERIAL"X7R"
PACK_TYPE"0402"
TOLERANCE"10%"
VALUE"0.220UF"
PART_NUMBER"A36096-104"
LOCATION"C1C12"
VOLTAGE"16V";
"A"
$PN"1"21;
"B"
$PN"2"20;
%"CAP"
"1","(-6025,3825)","0","mstr_discrete","I26";
;
CDS_SEC"1"
CDS_LIB"mstr_discrete"
SEC_TYPE"0402"
SEC"1"
CDS_LOCATION"C1C5"
ROOM"PVSA_CPU1_PWR_VR"
LOCATION"C1C5"
VALUE"1.0UF"
VOLTAGE"16V"
MATERIAL"X6S"
PART_NUMBER"D97712-011"
PACK_TYPE"0402"
TOLERANCE"10%";
"A"
$PN"1"30;
"B"
$PN"2"5;
%"CAP_A"
"1","(-6325,3850)","0","dev_discrete","I27";
;
CDS_LIB"dev_discrete"
CDS_LOCATION"C1C17"
ROOM"PVSA_CPU1_PWR_VR"
CDS_SEC"1"
SEC_TYPE"0402V"
SEC"1"
TOLERANCE"10%"
VOLTAGE"16V"
VALUE"0.1UF"
LOCATION"C1C17"
MATERIAL"X7R"
PACK_TYPE"0402V"
PART_NUMBER"A36096-030";
"B"
$PN"2"5;
"A"
$PN"1"3;
%"CAP"
"1","(-6600,3850)","0","mstr_discrete","I28";
;
CDS_SEC"1"
CDS_LIB"mstr_discrete"
CDS_LOCATION"C1C15"
SEC_TYPE"0402"
SEC"1"
ROOM"PVSA_CPU1_PWR_VR"
PACK_TYPE"0402"
VOLTAGE"16V"
VALUE"1.0UF"
LOCATION"C1C15"
PART_NUMBER"D97712-011"
MATERIAL"X6S"
TOLERANCE"10%";
"A"
$PN"1"3;
"B"
$PN"2"5;
%"RES"
"1","(-5300,2325)","0","mstr_discrete","I29";
;
CDS_SEC"1"
MATERIAL"CHIP"
BOM_COST"PROC_VRD_VCCIN_CPU0"
CDS_LIB"mstr_discrete"
ROOM"PVSA_CPU1_VSENSE_VR"
CDS_LOCATION"R1C12"
SEC"1"
SEC_TYPE"0402"
PART_NUMBER"G21796-017"
WATTAGE"1/16W"
VALUE"100.0"
PACK_TYPE"0402"
TOLERANCE"1%"
LOCATION"R1C12";
"B"
$PN"2"7;
"A"
$PN"1"23;
%"GND"
"1","(-4450,950)","0","mstr_symbols","I30";
;
BODY_TYPE"PLUMBING"
SIZE"1B"
CDS_LIB"mstr_symbols"
VOLTAGE"0"
BOM_COST"PROC_VRD_VCCIN_CPU0"
ROOM"PVSA_CPU1_VSENSE_VR"
HDL_POWER"GND";
"A\NAC"4;
%"RES"
"1","(-5275,1925)","0","mstr_discrete","I31";
;
CDS_SEC"1"
CDS_LIB"mstr_discrete"
CDS_LOCATION"R1C7"
ROOM"PVSA_CPU1_VSENSE_VR"
BOM_COST"PROC_VRD_VCCIN_CPU0"
SEC"1"
SEC_TYPE"0402"
WATTAGE"1/16W"
PACK_TYPE"0402"
VALUE"0.0"
MATERIAL"CHIP"
LOCATION"R1C7"
TOLERANCE"5%"
PART_NUMBER"G21497-005";
"B"
$PN"2"15;
"A"
$PN"1"23;
%"RES"
"1","(-5275,1475)","0","mstr_discrete","I32";
;
CDS_SEC"1"
CDS_LIB"mstr_discrete"
CDS_LOCATION"R1C5"
BOM_COST"PROC_VRD_VCCIN_CPU0"
ROOM"PVSA_CPU1_VSENSE_VR"
SEC"1"
SEC_TYPE"0402"
PART_NUMBER"G21497-005"
LOCATION"R1C5"
TOLERANCE"5%"
MATERIAL"CHIP"
WATTAGE"1/16W"
PACK_TYPE"0402"
VALUE"0.0";
"B"
$PN"2"26;
"A"
$PN"1"24;
%"RES"
"1","(-5275,1100)","0","mstr_discrete","I33";
;
CDS_SEC"1"
MATERIAL"CHIP"
CDS_LIB"mstr_discrete"
CDS_LOCATION"R1C4"
ROOM"PVSA_CPU1_VSENSE_VR"
BOM_COST"PROC_VRD_VCCIN_CPU0"
SEC_TYPE"0402"
SEC"1"
WATTAGE"1/16W"
PACK_TYPE"0402"
VALUE"100.0"
LOCATION"R1C4"
TOLERANCE"1%"
PART_NUMBER"G21796-017";
"B"
$PN"2"4;
"A"
$PN"1"24;
%"RES"
"2","(-5950,1725)","0","mstr_discrete","I34";
;
CDS_SEC"1"
CDS_LIB"mstr_discrete"
CDS_LOCATION"R1C6"
ROOM"PVSA_CPU1_VSENSE_VR"
BOM_COST"PROC_VRD_VCCIN_CPU0"
NO_XNET_CONNECTION"1"
SEC"1"
SEC_TYPE"0402"
VALUE"1.00K"
WATTAGE"1/16W"
TOLERANCE"1%"
LOCATION"R1C6"
MATERIAL"EMPTY"
PART_NUMBER"G21796-026"
PACK_TYPE"0402";
"A"
$PN"1"23;
"B"
$PN"2"24;
%"CAP"
"1","(-6850,3825)","0","mstr_discrete","I35";
;
CDS_SEC"1"
CDS_LIB"mstr_discrete"
ROOM"PVSA_CPU1_PWR_VR"
CDS_LOCATION"C9N13"
SEC"1"
SEC_TYPE"0805"
PART_NUMBER"C95333-007"
MATERIAL"X6S"
PACK_TYPE"0805"
TOLERANCE"10%"
VOLTAGE"16V"
VALUE"10UF"
LOCATION"C9N13";
"A"
$PN"1"3;
"B"
$PN"2"5;
%"CAP"
"1","(-7150,3850)","0","mstr_discrete","I36";
;
CDS_SEC"1"
CDS_LIB"mstr_discrete"
CDS_LOCATION"C9N19"
SEC"1"
SEC_TYPE"0805"
ROOM"PVSA_CPU1_PWR_VR"
PART_NUMBER"C95333-007"
VALUE"10UF"
MATERIAL"X6S"
TOLERANCE"10%"
PACK_TYPE"0805"
VOLTAGE"16V"
LOCATION"C9N19";
"A"
$PN"1"3;
"B"
$PN"2"5;
%"CAP"
"1","(-7400,3850)","0","mstr_discrete","I38";
;
CDS_SEC"1"
CDS_LIB"mstr_discrete"
CDS_LOCATION"C9N21"
ROOM"PVSA_CPU1_PWR_VR"
SEC_TYPE"0805"
SEC"1"
LOCATION"C9N21"
MATERIAL"X6S"
PACK_TYPE"0805"
TOLERANCE"10%"
VALUE"10UF"
VOLTAGE"16V"
PART_NUMBER"C95333-007";
"A"
$PN"1"3;
"B"
$PN"2"5;
%"GND"
"1","(-7400,3350)","0","mstr_symbols","I39";
;
ROOM"PVSA_CPU1_PWR_VR"
BOM_COST"PROC_VRD_VCCIN_CPU0"
BODY_TYPE"PLUMBING"
SIZE"1B"
CDS_LIB"mstr_symbols"
VOLTAGE"0"
HDL_POWER"GND";
"A\NAC"5;
%"P5V_STBY"
"1","(-4825,4575)","0","mstr_symbols","I42";
;
HDL_POWER"P5V_STBY"
BODY_TYPE"PLUMBING"
VOLTAGE"5.0V"
CDS_LIB"mstr_symbols"
SIZE"1B";
"G\NAC"6;
%"CAP_A"
"1","(-1050,3050)","0","dev_discrete","I44";
;
CDS_LIB"dev_discrete"
SEC"1"
SEC_TYPE"0603V"
CDS_SEC"1"
CDS_LOCATION"C9N22"
PART_NUMBER"E15431-004"
TOLERANCE"20%"
PACK_TYPE"0603V"
MATERIAL"X6S"
VOLTAGE"4V"
VALUE"22.0UF"
LOCATION"C9N22";
"B"
$PN"2"14;
"A"
$PN"1"13;
%"RES"
"2","(-625,3075)","0","mstr_discrete","I45";
;
CDS_LIB"mstr_discrete"
CDS_LOCATION"R9N4"
$SEC"1"
CDS_SEC"1"
PART_NUMBER"G21796-208"
PACK_TYPE"0402"
MATERIAL"CHIP"
WATTAGE"1/16W"
TOLERANCE"1.0%"
VALUE"51.1"
LOCATION"R9N4";
"A"
$PN"1"13;
"B"
$PN"2"14;
%"PVSA_CPU1"
"1","(-4575,2500)","0","mstr_symbols","I46";
;
VOLTAGE"1.1V"
BODY_TYPE"PLUMBING"
CDS_LIB"mstr_symbols"
BOM_COST"PROC_VRD_VCCIN_CPU0"
ROOM"PVSA_CPU1_PWR_VR"
HDL_POWER"PVSA_CPU1";
"G\NAC"7;
%"PVSA_CPU1"
"1","(-1325,1700)","0","mstr_symbols","I47";
;
BODY_TYPE"PLUMBING"
VOLTAGE"1.1V"
HDL_POWER"PVSA_CPU1"
CDS_LIB"mstr_symbols"
ROOM"PVSA_CPU1_PWR_VR"
BOM_COST"PROC_VRD_VCCIN_CPU0";
"G\NAC"8;
%"IR354XX"
"1","(-3725,3600)","0","mstr_discrete","I51";
;
CDS_SEC"1"
CDS_LOCATION"EU1C1"
SEC"1"
SEC_TYPE"SM"
PACK_TYPE"SM"
CDS_LIB"mstr_discrete"
PART_NUMBER"H73684-001"
MATERIAL"IC"
LOCATION"EU1C1"
VALUE"IR35412";
"TOUT_FLT"
$PN"36"17;
"NC"
$PN"31"29;
"OCSET"
$PN"37"25;
"IOUT"
$PN"38"28;
"SW"
$PN"10"16;
"BOOST"
$PN"33"19;
"REFIN"
$PN"39"18;
"PWM"
$PN"34"22;
"PHASE"
$PN"32"20;
"VIN<0>"
$PN"25"3;
"VCC"
$PN"3"30;
"VIN<1>"
$PN"30"3;
"EN"
$PN"35"6;
"VDRV"
$PN"4"6;
"VOS"
$PN"1"13;
"LGND"
$PN"2"2;
"PGND<1>"
$PN"7"2;
"PGND<2>"
$PN"40"2;
"PGND<0>"
$PN"5"2;
"GL<0>"
$PN"6"32;
"GL<1>"
$PN"41"31;
%"RES"
"2","(-1450,3775)","0","mstr_discrete","I52";
;
CDS_LOCATION"R1C37"
CDS_LIB"mstr_discrete"
CDS_SEC"1"
$SEC"1"
PACK_TYPE"0402"
TOLERANCE"1%"
WATTAGE"1/16W"
VALUE"68.1K"
PART_NUMBER"G21796-187"
LOCATION"R1C37"
MATERIAL"EMPTY";
"A"
$PN"1"25;
"B"
$PN"2"9;
%"GND"
"1","(-1450,3525)","0","mstr_symbols","I53";
;
ROOM"PVSA_CPU1_PWR_VR"
BOM_COST"PROC_VRD_VCCIN_CPU0"
BODY_TYPE"PLUMBING"
CDS_LIB"mstr_symbols"
SIZE"1B"
VOLTAGE"0"
HDL_POWER"GND";
"A\NAC"9;
%"GND"
"1","(-4450,2850)","0","mstr_symbols","I54";
;
BODY_TYPE"PLUMBING"
ROOM"PVCCIN_CPU0_PWR_VR"
BOM_COST"PROC_VRD_VCCIN_CPU0"
SIZE"1B"
VOLTAGE"0"
HDL_POWER"GND"
CDS_LIB"mstr_symbols";
"A\NAC"10;
%"CAP_A"
"1","(-4450,3100)","0","dev_discrete","I55";
;
CDS_SEC"1"
$SEC"1"
CDS_LOCATION"CT57"
ROOM"PVCCIN_CPU0_PWR_VR"
CDS_LIB"dev_discrete"
STATUS"NOPOP"
TOLERANCE"10%"
MATERIAL"X7R"
PART_NUMBER"A36096-030"
PACK_TYPE"0402V"
VOLTAGE"16V"
VALUE"0.1UF"
LOCATION"CT57";
"B"
$PN"2"10;
"A"
$PN"1"18;
%"SC2K2P50V3KX-GP"
"1","(-2500,3125)","0","w_hdl","I57";
;
CDS_SEC"1"
$SEC"1"
CDS_LOCATION"CT56"
PACK_TYPE"SMD-BCG6"
PART_NUMBER"78.22224.2BL"
CDS_LMAN_SYM_OUTLINE"-50,25,50,-25"
CDS_LIB"w_hdl"
VALUE"SC2K2P50V3KX-GP"
STATUS"NOPOP"
LOCATION"CT56";
"2"
$PN"2"27;
"1"
$PN"1"16;
%"GND"
"1","(-2500,2600)","0","mstr_symbols","I58";
;
HDL_POWER"GND"
SIZE"1B"
VOLTAGE"0"
BODY_TYPE"PLUMBING"
BOM_COST"PROC_VRD_VCCIN_CPU0"
ROOM"PVCCIN_CPU0_PWR_VR"
CDS_LIB"mstr_symbols";
"A\NAC"11;
%"3D01R5F-GP"
"1","(-2500,2825)","4","w_hdl","I59";
;
CDS_SEC"1"
$SEC"1"
CDS_LOCATION"RT38"
CDS_LMAN_SYM_OUTLINE"-50,75,50,-75"
CDS_LIB"w_hdl"
PART_NUMBER"64.3R015.16L"
PACK_TYPE"SMD-RG5"
VALUE"3D01R5F-GP"
LOCATION"RT38"
STATUS"NOPOP";
"2"
$PN"2"27;
"1"
$PN"1"11;
%"CAP"
"1","(-2650,3625)","0","mstr_discrete","I60";
;
CDS_SEC"1"
$SEC"1"
CDS_LOCATION"CT55"
CDS_LIB"mstr_discrete"
ROOM"VDDQ_KLM_PWR_VR"
LOCATION"CT55"
TOLERANCE"10%"
VOLTAGE"50V"
VALUE"1000PF"
STATUS"NOPOP"
PART_NUMBER"A36096-046"
MATERIAL"X7R"
PACK_TYPE"0402LF";
"A"
$PN"1"17;
"B"
$PN"2"12;
%"GND"
"1","(-2650,3425)","0","mstr_symbols","I61";
;
HDL_POWER"GND"
SIZE"1B"
BODY_TYPE"PLUMBING"
VOLTAGE"0"
ROOM"VDDQ_KLM_PWR_VR"
CDS_LIB"mstr_symbols";
"A\NAC"12;
%"RES"
"1","(-5425,3375)","0","mstr_discrete","I62";
;
CDS_SEC"1"
$SEC"1"
CDS_LOCATION"RT37"
CDS_LIB"mstr_discrete"
ROOM"BMC_DEBUG_HEADER"
BOM_COST"DEBUG"
VALUE"0.0"
TOLERANCE"5%"
MATERIAL"CHIP"
WATTAGE"1/16W"
LOCATION"RT37"
PART_NUMBER"G21497-005"
PACK_TYPE"0402";
"B"
$PN"2"19;
"A"
$PN"1"21;
%"PVSA_CPU1"
"1","(-625,3475)","0","mstr_symbols","I7";
;
VOLTAGE"1.1V"
CDS_LIB"mstr_symbols"
BODY_TYPE"PLUMBING"
HDL_POWER"PVSA_CPU1";
"G\NAC"13;
%"CAP_A"
"1","(-1400,3050)","0","dev_discrete","I8";
;
CDS_LIB"dev_discrete"
CDS_LOCATION"C1C19"
ROOM"PVSA_CPU1_PWR_VR"
BOM_COST"PROC_VRD_VCCIN_CPU0"
CDS_SEC"1"
SEC_TYPE"0603V"
SEC"1"
MATERIAL"X6S"
PACK_TYPE"0603V"
TOLERANCE"20%"
PART_NUMBER"E15431-004"
VOLTAGE"4V"
VALUE"22.0UF"
LOCATION"C1C19";
"B"
$PN"2"14;
"A"
$PN"1"13;
%"GND"
"1","(-1400,2700)","0","mstr_symbols","I9";
;
ROOM"PVSA_CPU1_PWR_VR"
BOM_COST"PROC_VRD_VCCIN_CPU0"
CDS_LIB"mstr_symbols"
VOLTAGE"0"
SIZE"1B"
BODY_TYPE"PLUMBING"
HDL_POWER"GND";
"A\NAC"14;
END.
